FILE_TYPE = MULTI_PHYS_TABLE;
PART 'MTG_KEYHOLE'
{===================================================================================================================================================================}
:PACK_TYPE | MATERIAL | PART_NUMBER    = EnvComp             | PART_NUMBER  | JEDEC_TYPE              | CLASS | DESCRIPTION                                                          | HEIGHT     | COMPONENT_TYPE  | SPEED_URL                                                                                                               | Status |RPL| AML | Bus_Unit | Days ;
{===================================================================================================================================================================}
'TH'       | 'EMPTY'  | 'NA'(!)        = ''                  | 'NA'         | 'MTG_KEYHOLE_196x295'   | 'IO'  | 'MTG_KEYHOLE, TOP 0.118IN, BOTTOM 0.196IN, 0.138IN CENTER-CENTER'    | '0.001 IN' | 'PSEUDO'        | 'http://speed.intel.com:8081/speed/module/pdm/item/pdm_item_detail_direct.asp?item_cde=NA&item_rev=01&url_param=unused' | '' | '' | '' | '' | '' 
'TH1'      | 'EMPTY'  | 'NA'(!)        = ''                  | 'NA'         | 'MTG_KEYHOLE_N384X236A' | 'IO'  | 'NPTH KEYHOLE WITH T/B PADS, L=0.236IN, R=0.136IN, C-C=0.197IN'      | '0.001 IN' | 'PSEUDO'        | 'http://speed.intel.com:8081/speed/module/pdm/item/pdm_item_detail_direct.asp?item_cde=NA&item_rev=01&url_param=unused' | '' | '' | '' | '' | '' 
END_PART
END.
